# T6G (Grand Teton) — schematic netlist excerpt (pin names and nets, part order shuffled) for the footprints in the layout excerpt that follows; sources: Cadence DE-HDL packaged netlist, KiCad conversion of 04192023_DAF0TMB3IC0_F0TG_MB_C_brd_V02_OCP.brd

C2164  Q_CAP  22UF 4V 20% X6S  pkg C0402  page 68 : A = PVDD18_S5_P0 ; B = GND
C2423  Q_CAP  22UF 4V 20% X6S  pkg C0402  page 74 : A = PVDDCR_SOC_P1 ; B = GND

(kicad_pcb
	(version 20260206)
	(generator "pcbnew")
	(generator_version "10.0")
	(general
		(thickness 1.6)
		(legacy_teardrops no)
	)
	(paper "A4")
	(title_block
		(title "04192023_DAF0TMB3IC0_F0TG_MB_C_brd_V02_OCP.brd")
		(comment 1 "Grand Teton / footprints 4488-4489 of 8354")
	)
	(layers
		(0 "F.Cu" signal "TOP")
		(4 "In1.Cu" signal "GND")
		(6 "In2.Cu" signal "IN1")
		(8 "In3.Cu" signal "GND1")
		(10 "In4.Cu" signal "IN2")
		(12 "In5.Cu" signal "GND2")
		(14 "In6.Cu" signal "IN3")
		(16 "In7.Cu" signal "GND3")
		(18 "In8.Cu" signal "VCC")
		(20 "In9.Cu" signal "VCC1")
		(22 "In10.Cu" signal "GND4")
		(24 "In11.Cu" signal "IN4")
		(26 "In12.Cu" signal "GND5")
		(28 "In13.Cu" signal "IN5")
		(30 "In14.Cu" signal "GND6")
		(32 "In15.Cu" signal "IN6")
		(34 "In16.Cu" signal "GND7")
		(2 "B.Cu" signal "BOTTOM")
		(9 "F.Adhes" user "F.Adhesive")
		(11 "B.Adhes" user "B.Adhesive")
		(13 "F.Paste" user "Package Geometry/Pastemask Top")
		(15 "B.Paste" user "Package Geometry/Pastemask Bottom")
		(5 "F.SilkS" user "Ref Des/Silkscreen Top")
		(7 "B.SilkS" user "Ref Des/Silkscreen Bottom")
		(1 "F.Mask" user "Board Geometry/Soldermask Top")
		(3 "B.Mask" user "Board Geometry/Soldermask Bottom")
		(17 "Dwgs.User" user "User.Drawings")
		(19 "Cmts.User" user "User.Comments")
		(21 "Eco1.User" user "User.Eco1")
		(23 "Eco2.User" user "User.Eco2")
		(25 "Edge.Cuts" user "Board Geometry/Outline")
		(27 "Margin" user)
		(31 "F.CrtYd" user "Package Geometry/Place Bound Top")
		(29 "B.CrtYd" user "Package Geometry/Place Bound Bottom")
		(35 "F.Fab" user "Ref Des/Assembly Top")
		(33 "B.Fab" user "Ref Des/Assembly Bottom")
	)
	(footprint ""
		(layer "F.Cu")
		(at 115.70589 -257.74523)
		(property "Reference" "C2423"
			(at 0 0 0)
			(layer "F.SilkS")
			(hide yes)
			(effects
				(font
					(size 1.27 1.27)
				)
			)
		)
		(property "Value" ""
			(at 0 0 0)
			(layer "F.Fab")
			(effects
				(font
					(size 1.27 1.27)
				)
			)
		)
		(duplicate_pad_numbers_are_jumpers no)
		(fp_line
			(start -0.7874 -0.4064)
			(end 0.7874 -0.4064)
			(stroke
				(width 0.1524)
				(type default)
			)
			(layer "F.SilkS")
		)
		(fp_line
			(start -0.7874 0.4064)
			(end -0.7874 -0.4064)
			(stroke
				(width 0.1524)
				(type default)
			)
			(layer "F.SilkS")
		)
		(fp_line
			(start 0.7874 -0.4064)
			(end 0.7874 0.4064)
			(stroke
				(width 0.1524)
				(type default)
			)
			(layer "F.SilkS")
		)
		(fp_line
			(start 0.7874 0.4064)
			(end -0.7874 0.4064)
			(stroke
				(width 0.1524)
				(type default)
			)
			(layer "F.SilkS")
		)
		(fp_line
			(start -0.67945 -0.305054)
			(end -0.12065 -0.305054)
			(stroke
				(width 0.1)
				(type default)
			)
			(layer "F.Fab")
		)
		(fp_line
			(start -0.67945 0.3048)
			(end -0.67945 -0.305054)
			(stroke
				(width 0.1)
				(type default)
			)
			(layer "F.Fab")
		)
		(fp_line
			(start -0.12065 -0.305054)
			(end -0.12065 -0.2794)
			(stroke
				(width 0.1)
				(type default)
			)
			(layer "F.Fab")
		)
		(fp_line
			(start -0.12065 -0.2794)
			(end 0.12065 -0.2794)
			(stroke
				(width 0.1)
				(type default)
			)
			(layer "F.Fab")
		)
		(fp_line
			(start -0.12065 0.2794)
			(end -0.12065 0.3048)
			(stroke
				(width 0.1)
				(type default)
			)
			(layer "F.Fab")
		)
		(fp_line
			(start -0.12065 0.3048)
			(end -0.67945 0.3048)
			(stroke
				(width 0.1)
				(type default)
			)
			(layer "F.Fab")
		)
		(fp_line
			(start 0.120396 0.2794)
			(end -0.12065 0.2794)
			(stroke
				(width 0.1)
				(type default)
			)
			(layer "F.Fab")
		)
		(fp_line
			(start 0.120396 0.3048)
			(end 0.120396 0.2794)
			(stroke
				(width 0.1)
				(type default)
			)
			(layer "F.Fab")
		)
		(fp_line
			(start 0.12065 -0.3048)
			(end 0.67945 -0.3048)
			(stroke
				(width 0.1)
				(type default)
			)
			(layer "F.Fab")
		)
		(fp_line
			(start 0.12065 -0.2794)
			(end 0.12065 -0.3048)
			(stroke
				(width 0.1)
				(type default)
			)
			(layer "F.Fab")
		)
		(fp_line
			(start 0.67945 -0.3048)
			(end 0.67945 0.3048)
			(stroke
				(width 0.1)
				(type default)
			)
			(layer "F.Fab")
		)
		(fp_line
			(start 0.67945 0.3048)
			(end 0.120396 0.3048)
			(stroke
				(width 0.1)
				(type default)
			)
			(layer "F.Fab")
		)
		(pad "1" smd circle
			(at -0.40005 0)
			(size 0 0)
			(layers "F.Cu" "F.Mask" "F.Paste")
			(net "PVDDCR_SOC_P1")
		)
		(pad "2" smd circle
			(at 0.40005 0)
			(size 0 0)
			(layers "F.Cu" "F.Mask" "F.Paste")
			(net "GND")
		)
	)
	(footprint ""
		(layer "F.Cu")
		(at 353.900232 -255.554988)
		(property "Reference" "C2164"
			(at 0 0 0)
			(layer "F.SilkS")
			(hide yes)
			(effects
				(font
					(size 1.27 1.27)
				)
			)
		)
		(property "Value" ""
			(at 0 0 0)
			(layer "F.Fab")
			(effects
				(font
					(size 1.27 1.27)
				)
			)
		)
		(duplicate_pad_numbers_are_jumpers no)
		(fp_line
			(start -0.7874 -0.4064)
			(end 0.7874 -0.4064)
			(stroke
				(width 0.1524)
				(type default)
			)
			(layer "F.SilkS")
		)
		(fp_line
			(start -0.7874 0.4064)
			(end -0.7874 -0.4064)
			(stroke
				(width 0.1524)
				(type default)
			)
			(layer "F.SilkS")
		)
		(fp_line
			(start 0.7874 -0.4064)
			(end 0.7874 0.4064)
			(stroke
				(width 0.1524)
				(type default)
			)
			(layer "F.SilkS")
		)
		(fp_line
			(start 0.7874 0.4064)
			(end -0.7874 0.4064)
			(stroke
				(width 0.1524)
				(type default)
			)
			(layer "F.SilkS")
		)
		(fp_line
			(start -0.67945 -0.305054)
			(end -0.12065 -0.305054)
			(stroke
				(width 0.1)
				(type default)
			)
			(layer "F.Fab")
		)
		(fp_line
			(start -0.67945 0.3048)
			(end -0.67945 -0.305054)
			(stroke
				(width 0.1)
				(type default)
			)
			(layer "F.Fab")
		)
		(fp_line
			(start -0.12065 -0.305054)
			(end -0.12065 -0.2794)
			(stroke
				(width 0.1)
				(type default)
			)
			(layer "F.Fab")
		)
		(fp_line
			(start -0.12065 -0.2794)
			(end 0.12065 -0.2794)
			(stroke
				(width 0.1)
				(type default)
			)
			(layer "F.Fab")
		)
		(fp_line
			(start -0.12065 0.2794)
			(end -0.12065 0.3048)
			(stroke
				(width 0.1)
				(type default)
			)
			(layer "F.Fab")
		)
		(fp_line
			(start -0.12065 0.3048)
			(end -0.67945 0.3048)
			(stroke
				(width 0.1)
				(type default)
			)
			(layer "F.Fab")
		)
		(fp_line
			(start 0.120396 0.2794)
			(end -0.12065 0.2794)
			(stroke
				(width 0.1)
				(type default)
			)
			(layer "F.Fab")
		)
		(fp_line
			(start 0.120396 0.3048)
			(end 0.120396 0.2794)
			(stroke
				(width 0.1)
				(type default)
			)
			(layer "F.Fab")
		)
		(fp_line
			(start 0.12065 -0.3048)
			(end 0.67945 -0.3048)
			(stroke
				(width 0.1)
				(type default)
			)
			(layer "F.Fab")
		)
		(fp_line
			(start 0.12065 -0.2794)
			(end 0.12065 -0.3048)
			(stroke
				(width 0.1)
				(type default)
			)
			(layer "F.Fab")
		)
		(fp_line
			(start 0.67945 -0.3048)
			(end 0.67945 0.3048)
			(stroke
				(width 0.1)
				(type default)
			)
			(layer "F.Fab")
		)
		(fp_line
			(start 0.67945 0.3048)
			(end 0.120396 0.3048)
			(stroke
				(width 0.1)
				(type default)
			)
			(layer "F.Fab")
		)
		(pad "1" smd circle
			(at -0.40005 0)
			(size 0 0)
			(layers "F.Cu" "F.Mask" "F.Paste")
			(net "PVDD18_S5_P0")
		)
		(pad "2" smd circle
			(at 0.40005 0)
			(size 0 0)
			(layers "F.Cu" "F.Mask" "F.Paste")
			(net "GND")
		)
	)
)
